(kicad_pcb
	(version 20260206)
	(generator "pcbnew")
	(generator_version "10.0")
	(general
		(thickness 1.6)
		(legacy_teardrops no)
	)
	(paper "A4")
	(title_block
		(title "netronome-mezz — pcbd0082-001_rev01_jul9_a.brd")
		(comment 1 "Open CloudServer (Microsoft) / footprints 182-185 of 714")
	)
	(layers
		(0 "F.Cu" signal "TOP")
		(4 "In1.Cu" signal "02_GND")
		(6 "In2.Cu" signal "03_SIG")
		(8 "In3.Cu" signal "04_SIG")
		(10 "In4.Cu" signal "05_GND")
		(12 "In5.Cu" signal "06_PWR1")
		(14 "In6.Cu" signal "07_SIG")
		(16 "In7.Cu" signal "08_SIG")
		(18 "In8.Cu" signal "09_GND")
		(2 "B.Cu" signal "BOTTOM")
		(9 "F.Adhes" user "F.Adhesive")
		(11 "B.Adhes" user "B.Adhesive")
		(13 "F.Paste" user "Package Geometry/Pastemask Top")
		(15 "B.Paste" user "Package Geometry/Pastemask Bottom")
		(5 "F.SilkS" user "Ref Des/Silkscreen Top")
		(7 "B.SilkS" user "Ref Des/Silkscreen Bottom")
		(1 "F.Mask" user "Board Geometry/Soldermask Top")
		(3 "B.Mask" user "Board Geometry/Soldermask Bottom")
		(17 "Dwgs.User" user "User.Drawings")
		(19 "Cmts.User" user "User.Comments")
		(21 "Eco1.User" user "User.Eco1")
		(23 "Eco2.User" user "User.Eco2")
		(25 "Edge.Cuts" user "Board Geometry/Outline")
		(27 "Margin" user)
		(31 "F.CrtYd" user "Package Geometry/Place Bound Top")
		(29 "B.CrtYd" user "Package Geometry/Place Bound Bottom")
		(35 "F.Fab" user "Ref Des/Assembly Top")
		(33 "B.Fab" user "Ref Des/Assembly Bottom")
		(45 "User.4" user "COMPVAL_TYPE_BOTTOM")
	)
	(footprint ""
		(layer "F.Cu")
		(at 14.478 37.211 90)
		(property "Reference" "U9"
			(at 2.64033 -3.81 0)
			(unlocked yes)
			(layer "F.SilkS")
			(effects
				(font
					(size 0.7874 0.5842)
					(thickness 0.127)
				)
				(justify left)
			)
		)
		(property "Value" "VAL"
			(at 0 1.851914 90)
			(unlocked yes)
			(layer "F.Fab")
			(hide yes)
			(effects
				(font
					(size 1.27 0.9652)
					(thickness 0.1524)
				)
			)
		)
		(property "User Part Number" "PN"
			(at 0 -4.148328 90)
			(unlocked yes)
			(layer "Cmts.User")
			(hide yes)
			(effects
				(font
					(size 1.27 0.9652)
					(thickness 0.1524)
				)
			)
		)
		(property "Device Type" "DCDC0065"
			(at 0 -1.898142 90)
			(unlocked yes)
			(layer "F.Fab")
			(hide yes)
			(effects
				(font
					(size 1.27 0.9652)
					(thickness 0.1524)
				)
			)
		)
		(property "Tolerance" "TOL"
			(at 0 4.144518 90)
			(unlocked yes)
			(layer "Cmts.User")
			(hide yes)
			(effects
				(font
					(size 1.27 0.9652)
					(thickness 0.1524)
				)
			)
		)
		(duplicate_pad_numbers_are_jumpers no)
		(fp_line
			(start 2.355088 -2.355088)
			(end 2.355088 -1.905)
			(stroke
				(width 0.1524)
				(type default)
			)
			(layer "F.SilkS")
		)
		(fp_line
			(start 1.905 -2.355088)
			(end 2.355088 -2.355088)
			(stroke
				(width 0.1524)
				(type default)
			)
			(layer "F.SilkS")
		)
		(fp_line
			(start -1.955013 -2.355088)
			(end -1.905 -2.355088)
			(stroke
				(width 0.1524)
				(type default)
			)
			(layer "F.SilkS")
		)
		(fp_line
			(start -2.355088 -1.955013)
			(end -1.955013 -2.355088)
			(stroke
				(width 0.1524)
				(type default)
			)
			(layer "F.SilkS")
		)
		(fp_line
			(start -2.355088 -1.905)
			(end -2.355088 -1.955013)
			(stroke
				(width 0.1524)
				(type default)
			)
			(layer "F.SilkS")
		)
		(fp_line
			(start 2.355088 1.905)
			(end 2.355088 2.355088)
			(stroke
				(width 0.1524)
				(type default)
			)
			(layer "F.SilkS")
		)
		(fp_line
			(start 2.355088 2.355088)
			(end 1.905 2.355088)
			(stroke
				(width 0.1524)
				(type default)
			)
			(layer "F.SilkS")
		)
		(fp_line
			(start -1.905 2.355088)
			(end -2.355088 2.355088)
			(stroke
				(width 0.1524)
				(type default)
			)
			(layer "F.SilkS")
		)
		(fp_line
			(start -2.355088 2.355088)
			(end -2.355088 1.905)
			(stroke
				(width 0.1524)
				(type default)
			)
			(layer "F.SilkS")
		)
		(fp_arc
			(start -2.8956 -2.032)
			(mid -2.876496 -2.031281)
			(end -2.8575 -2.02913)
			(stroke
				(width 0.1524)
				(type default)
			)
			(layer "F.SilkS")
		)
		(fp_arc
			(start -2.921 -2.03073)
			(mid -2.908316 -2.031684)
			(end -2.8956 -2.032)
			(stroke
				(width 0.1524)
				(type default)
			)
			(layer "F.SilkS")
		)
		(fp_arc
			(start -2.8575 -1.52687)
			(mid -2.876496 -1.524717)
			(end -2.8956 -1.524)
			(stroke
				(width 0.1524)
				(type default)
			)
			(layer "F.SilkS")
		)
		(fp_arc
			(start -2.8956 -1.524)
			(mid -2.965173 -1.533714)
			(end -3.029433 -1.5621)
			(stroke
				(width 0.1524)
				(type default)
			)
			(layer "F.SilkS")
		)
		(fp_circle
			(center -2.8956 -1.778)
			(end -2.8956 -1.524)
			(stroke
				(width 0.1524)
				(type default)
			)
			(fill no)
			(layer "F.SilkS")
		)
		(fp_poly
			(pts
				(xy -3.048 3.048) (xy 3.048 3.048) (xy 3.048 -3.048) (xy -3.048 -3.048)
			)
			(stroke
				(width 0)
				(type default)
			)
			(fill no)
			(layer "F.CrtYd")
		)
		(fp_line
			(start 2.275103 -2.275103)
			(end 2.275103 2.275103)
			(stroke
				(width 0.0254)
				(type default)
			)
			(layer "F.Fab")
		)
		(fp_line
			(start -1.640103 -2.275103)
			(end 2.275103 -2.275103)
			(stroke
				(width 0.0254)
				(type default)
			)
			(layer "F.Fab")
		)
		(fp_line
			(start -2.275103 -1.640103)
			(end -1.640103 -2.275103)
			(stroke
				(width 0.0254)
				(type default)
			)
			(layer "F.Fab")
		)
		(fp_line
			(start 2.275103 2.275103)
			(end -2.275103 2.275103)
			(stroke
				(width 0.0254)
				(type default)
			)
			(layer "F.Fab")
		)
		(fp_line
			(start -2.275103 2.275103)
			(end -2.275103 -1.640103)
			(stroke
				(width 0.0254)
				(type default)
			)
			(layer "F.Fab")
		)
		(fp_circle
			(center -1.61511 -1.61511)
			(end -1.61511 -1.361212)
			(stroke
				(width 0.0254)
				(type default)
			)
			(fill no)
			(layer "F.Fab")
		)
		(pad "1" smd custom
			(at -2.1717 -1.599895)
			(size 0.0508 0.0508)
			(layers "F.Cu" "F.Mask" "F.Paste")
			(net "11N1968")
			(options
				(clearance outline)
				(anchor circle)
			)
			(primitives
				(gr_poly
					(pts
						(xy -0.1016 0.3556) (xy -0.1016 -0.254) (xy 0 -0.3556) (xy 0.1016 -0.3556) (xy 0.1016 0.3556)
					)
					(width 0)
					(fill yes)
				)
			)
		)
		(pad "2" smd rect
			(at -2.1717 -1.199896)
			(size 0.2032 0.7112)
			(layers "F.Cu" "F.Mask" "F.Paste")
			(net "VDD_5.0V")
		)
		(pad "3" smd rect
			(at -2.1717 -0.8001)
			(size 0.2032 0.7112)
			(layers "F.Cu" "F.Mask" "F.Paste")
			(net "VDD_1.5V")
		)
		(pad "4" smd rect
			(at -2.1717 -0.399999)
			(size 0.2032 0.7112)
			(layers "F.Cu" "F.Mask" "F.Paste")
			(net "VDD_5.0V")
		)
		(pad "5" smd rect
			(at -2.1717 0)
			(size 0.2032 0.7112)
			(layers "F.Cu" "F.Mask" "F.Paste")
			(net "11N1937")
		)
		(pad "6" smd rect
			(at -2.1717 0.399999)
			(size 0.2032 0.7112)
			(layers "F.Cu" "F.Mask" "F.Paste")
			(net "GND")
		)
		(pad "7" smd rect
			(at -2.1717 0.8001)
			(size 0.2032 0.7112)
			(layers "F.Cu" "F.Mask" "F.Paste")
			(net "VDD_1.8V")
		)
		(pad "8" smd rect
			(at -2.1717 1.199896)
			(size 0.2032 0.7112)
			(layers "F.Cu" "F.Mask" "F.Paste")
			(net "VDD_5.0V")
		)
		(pad "9" smd custom
			(at -2.1717 1.599895)
			(size 0.0508 0.0508)
			(layers "F.Cu" "F.Mask" "F.Paste")
			(net "11N1971")
			(options
				(clearance outline)
				(anchor circle)
			)
			(primitives
				(gr_poly
					(pts
						(xy 0.1016 0.3556) (xy 0.1016 -0.254) (xy 0 -0.3556) (xy -0.1016 -0.3556) (xy -0.1016 0.3556)
					)
					(width 0)
					(fill yes)
				)
			)
		)
		(pad "10" smd custom
			(at -1.599895 2.1717 90)
			(size 0.0508 0.0508)
			(layers "F.Cu" "F.Mask" "F.Paste")
			(net "GND")
			(options
				(clearance outline)
				(anchor circle)
			)
			(primitives
				(gr_poly
					(pts
						(xy -0.1016 0.3556) (xy -0.1016 -0.254) (xy 0 -0.3556) (xy 0.1016 -0.3556) (xy 0.1016 0.3556)
					)
					(width 0)
					(fill yes)
				)
			)
		)
		(pad "11" smd rect
			(at -1.199896 2.1717 90)
			(size 0.2032 0.7112)
			(layers "F.Cu" "F.Mask" "F.Paste")
			(net "DDR_1.8V")
		)
		(pad "12" smd rect
			(at -0.8001 2.1717 90)
			(size 0.2032 0.7112)
			(layers "F.Cu" "F.Mask" "F.Paste")
			(net "11N1979")
		)
		(pad "13" smd rect
			(at -0.399999 2.1717 90)
			(size 0.2032 0.7112)
			(layers "F.Cu" "F.Mask" "F.Paste")
			(net "PSU_I2C_SDA")
		)
		(pad "14" smd rect
			(at 0 2.1717 90)
			(size 0.2032 0.7112)
			(layers "F.Cu" "F.Mask" "F.Paste")
			(net "GND")
		)
		(pad "15" smd rect
			(at 0.399999 2.1717 90)
			(size 0.2032 0.7112)
			(layers "F.Cu" "F.Mask" "F.Paste")
			(net "PSU_I2C_SCL")
		)
		(pad "16" smd rect
			(at 0.8001 2.1717 90)
			(size 0.2032 0.7112)
			(layers "F.Cu" "F.Mask" "F.Paste")
			(net "11N1966")
		)
		(pad "17" smd rect
			(at 1.199896 2.1717 90)
			(size 0.2032 0.7112)
			(layers "F.Cu" "F.Mask" "F.Paste")
			(net "VDD_3.3V")
		)
		(pad "18" smd custom
			(at 1.599895 2.1717 90)
			(size 0.0508 0.0508)
			(layers "F.Cu" "F.Mask" "F.Paste")
			(net "GND")
			(options
				(clearance outline)
				(anchor circle)
			)
			(primitives
				(gr_poly
					(pts
						(xy 0.1016 0.3556) (xy 0.1016 -0.254) (xy 0 -0.3556) (xy -0.1016 -0.3556) (xy -0.1016 0.3556)
					)
					(width 0)
					(fill yes)
				)
			)
		)
		(pad "19" smd custom
			(at 2.1717 1.599895 180)
			(size 0.0508 0.0508)
			(layers "F.Cu" "F.Mask" "F.Paste")
			(net "11N2296")
			(options
				(clearance outline)
				(anchor circle)
			)
			(primitives
				(gr_poly
					(pts
						(xy -0.1016 0.3556) (xy -0.1016 -0.254) (xy 0 -0.3556) (xy 0.1016 -0.3556) (xy 0.1016 0.3556)
					)
					(width 0)
					(fill yes)
				)
			)
		)
		(pad "20" smd rect
			(at 2.1717 1.199896 180)
			(size 0.2032 0.7112)
			(layers "F.Cu" "F.Mask" "F.Paste")
			(net "VDD_5.0V")
		)
		(pad "21" smd rect
			(at 2.1717 0.8001 180)
			(size 0.2032 0.7112)
			(layers "F.Cu" "F.Mask" "F.Paste")
			(net "VDD_5.0V")
		)
		(pad "22" smd rect
			(at 2.1717 0.399999 180)
			(size 0.2032 0.7112)
			(layers "F.Cu" "F.Mask" "F.Paste")
			(net "GND")
		)
		(pad "23" smd rect
			(at 2.1717 0 180)
			(size 0.2032 0.7112)
			(layers "F.Cu" "F.Mask" "F.Paste")
			(net "GND")
		)
		(pad "24" smd rect
			(at 2.1717 -0.399999 180)
			(size 0.2032 0.7112)
			(layers "F.Cu" "F.Mask" "F.Paste")
			(net "VDD_5.0V")
		)
		(pad "25" smd rect
			(at 2.1717 -0.8001 180)
			(size 0.2032 0.7112)
			(layers "F.Cu" "F.Mask" "F.Paste")
			(net "VDD_5.0V")
		)
		(pad "26" smd rect
			(at 2.1717 -1.199896 180)
			(size 0.2032 0.7112)
			(layers "F.Cu" "F.Mask" "F.Paste")
			(net "VDD_5.0V")
		)
		(pad "27" smd custom
			(at 2.1717 -1.599895 180)
			(size 0.0508 0.0508)
			(layers "F.Cu" "F.Mask" "F.Paste")
			(net "11N1970")
			(options
				(clearance outline)
				(anchor circle)
			)
			(primitives
				(gr_poly
					(pts
						(xy 0.1016 0.3556) (xy 0.1016 -0.254) (xy 0 -0.3556) (xy -0.1016 -0.3556) (xy -0.1016 0.3556)
					)
					(width 0)
					(fill yes)
				)
			)
		)
		(pad "28" smd custom
			(at 1.599895 -2.1717 270)
			(size 0.0508 0.0508)
			(layers "F.Cu" "F.Mask" "F.Paste")
			(net "GND")
			(options
				(clearance outline)
				(anchor circle)
			)
			(primitives
				(gr_poly
					(pts
						(xy -0.1016 0.3556) (xy -0.1016 -0.254) (xy 0 -0.3556) (xy 0.1016 -0.3556) (xy 0.1016 0.3556)
					)
					(width 0)
					(fill yes)
				)
			)
		)
		(pad "29" smd rect
			(at 1.199896 -2.1717 270)
			(size 0.2032 0.7112)
			(layers "F.Cu" "F.Mask" "F.Paste")
			(net "VDD_1.2V")
		)
		(pad "30" smd rect
			(at 0.8001 -2.1717 270)
			(size 0.2032 0.7112)
			(layers "F.Cu" "F.Mask" "F.Paste")
			(net "VDD_7401_EN")
		)
		(pad "31" smd rect
			(at 0.399999 -2.1717 270)
			(size 0.2032 0.7112)
			(layers "F.Cu" "F.Mask" "F.Paste")
			(net "VDD_5.0V")
		)
		(pad "32" smd rect
			(at 0 -2.1717 270)
			(size 0.2032 0.7112)
			(layers "F.Cu" "F.Mask" "F.Paste")
			(net "GND")
		)
		(pad "33" smd rect
			(at -0.399999 -2.1717 270)
			(size 0.2032 0.7112)
			(layers "F.Cu" "F.Mask" "F.Paste")
			(net "_NC_MIC7401_NC1")
		)
		(pad "34" smd rect
			(at -0.8001 -2.1717 270)
			(size 0.2032 0.7112)
			(layers "F.Cu" "F.Mask" "F.Paste")
			(net "_NC_MIC7401_NC2")
		)
		(pad "35" smd rect
			(at -1.199896 -2.1717 270)
			(size 0.2032 0.7112)
			(layers "F.Cu" "F.Mask" "F.Paste")
			(net "VDD_7401_PGOOD")
		)
		(pad "36" smd custom
			(at -1.599895 -2.1717 270)
			(size 0.0508 0.0508)
			(layers "F.Cu" "F.Mask" "F.Paste")
			(net "GND")
			(options
				(clearance outline)
				(anchor circle)
			)
			(primitives
				(gr_poly
					(pts
						(xy 0.1016 0.3556) (xy 0.1016 -0.254) (xy 0 -0.3556) (xy -0.1016 -0.3556) (xy -0.1016 0.3556)
					)
					(width 0)
					(fill yes)
				)
			)
		)
		(pad "37" smd rect
			(at 0 0 90)
			(size 1.8034 1.8034)
			(layers "F.Cu" "F.Mask" "F.Paste")
			(net "GND")
		)
	)
	(footprint ""
		(layer "F.Cu")
		(at 53.086 49.5046 -90)
		(property "Reference" "C63"
			(at 1.32207 -0.127 0)
			(unlocked yes)
			(layer "F.SilkS")
			(effects
				(font
					(size 0.7874 0.5842)
					(thickness 0.127)
				)
				(justify left)
			)
		)
		(property "Value" "100UF"
			(at -0.78232 0.4826 0)
			(unlocked yes)
			(layer "F.Fab")
			(hide yes)
			(effects
				(font
					(size 1.27 0.9652)
					(thickness 0.000001)
				)
				(justify left)
			)
		)
		(property "Device Type" "CAPC0087"
			(at -0.78232 0.4826 0)
			(unlocked yes)
			(layer "F.Fab")
			(hide yes)
			(effects
				(font
					(size 1.27 0.9652)
					(thickness 0.000001)
				)
				(justify left)
			)
		)
		(duplicate_pad_numbers_are_jumpers no)
		(fp_circle
			(center 0 0)
			(end 0 -0.508)
			(stroke
				(width 0.2032)
				(type default)
			)
			(fill no)
			(layer "F.SilkS")
		)
		(fp_circle
			(center 0 0)
			(end 0 -0.508)
			(stroke
				(width 0.2032)
				(type default)
			)
			(fill no)
			(layer "F.SilkS")
		)
		(fp_poly
			(pts
				(xy -1.27 2.9464) (xy 1.27 2.9464) (xy 1.27 -2.9464) (xy -1.27 -2.9464)
			)
			(stroke
				(width 0)
				(type default)
			)
			(fill no)
			(layer "F.CrtYd")
		)
		(fp_line
			(start -1.016 2.794)
			(end -1.016 -2.794)
			(stroke
				(width 0.0254)
				(type default)
			)
			(layer "F.Fab")
		)
		(fp_line
			(start 1.016 2.794)
			(end -1.016 2.794)
			(stroke
				(width 0.0254)
				(type default)
			)
			(layer "F.Fab")
		)
		(fp_line
			(start -1.016 -2.794)
			(end 1.016 -2.794)
			(stroke
				(width 0.0254)
				(type default)
			)
			(layer "F.Fab")
		)
		(fp_line
			(start 1.016 -2.794)
			(end 1.016 2.794)
			(stroke
				(width 0.0254)
				(type default)
			)
			(layer "F.Fab")
		)
		(pad "1" smd rect
			(at 0 -1.6764 270)
			(size 1.524 1.524)
			(layers "F.Cu" "F.Mask" "F.Paste")
			(net "VDD_CORE")
		)
		(pad "2" smd rect
			(at 0 1.6764 270)
			(size 1.524 1.524)
			(layers "F.Cu" "F.Mask" "F.Paste")
			(net "GND")
		)
		(zone
			(layer "F.Cu")
			(hatch none 0.5)
			(connect_pads
				(clearance 0)
			)
			(min_thickness 0.25)
			(keepout
				(tracks allowed)
				(vias not_allowed)
				(pads allowed)
				(copperpour not_allowed)
				(footprints allowed)
			)
			(placement
				(enabled no)
				(sheetname "")
			)
			(fill
				(thermal_gap 0.5)
				(thermal_bridge_width 0.5)
				(island_removal_mode 0)
			)
			(polygon
				(pts
					(xy 51.4858 48.7172) (xy 51.4858 50.292) (xy 54.6862 50.292) (xy 54.6862 48.7172)
				)
			)
		)
		(zone
			(layer "F.Cu")
			(hatch none 0.5)
			(connect_pads
				(clearance 0)
			)
			(min_thickness 0.25)
			(keepout
				(tracks not_allowed)
				(vias allowed)
				(pads allowed)
				(copperpour not_allowed)
				(footprints allowed)
			)
			(placement
				(enabled no)
				(sheetname "")
			)
			(fill
				(thermal_gap 0.5)
				(thermal_bridge_width 0.5)
				(island_removal_mode 0)
			)
			(polygon
				(pts
					(xy 52.3494 48.7172) (xy 52.3494 50.292) (xy 52.197 50.292) (xy 52.197 48.7172)
				)
			)
		)
		(zone
			(layer "F.Cu")
			(hatch none 0.5)
			(connect_pads
				(clearance 0)
			)
			(min_thickness 0.25)
			(keepout
				(tracks not_allowed)
				(vias allowed)
				(pads allowed)
				(copperpour not_allowed)
				(footprints allowed)
			)
			(placement
				(enabled no)
				(sheetname "")
			)
			(fill
				(thermal_gap 0.5)
				(thermal_bridge_width 0.5)
				(island_removal_mode 0)
			)
			(polygon
				(pts
					(xy 53.975 48.7172) (xy 53.975 50.292) (xy 53.8226 50.292) (xy 53.8226 48.7172)
				)
			)
		)
	)
	(footprint ""
		(layer "F.Cu")
		(at 73.05101 7.498994)
		(property "Reference" "V_A-DQ10"
			(at 0 0 0)
			(layer "F.SilkS")
			(hide yes)
			(effects
				(font
					(size 1.27 1.27)
				)
			)
		)
		(property "Value" ""
			(at 0 0 0)
			(layer "F.Fab")
			(effects
				(font
					(size 1.27 1.27)
				)
			)
		)
		(duplicate_pad_numbers_are_jumpers no)
		(pad "1" thru_hole circle
			(at 0 0)
			(size 0.762 0.762)
			(drill 0.20574)
			(layers "*.Cu" "*.Mask")
			(remove_unused_layers no)
			(net "DDR0_32A_DQ10")
			(clearance 0.127)
			(thermal_gap 0.127)
			(padstack
				(mode front_inner_back)
				(layer "Inner"
					(shape circle)
					(size 0.4572 0.4572)
					(clearance 0.1143)
				)
				(layer "B.Cu"
					(shape circle)
					(size 0.4572 0.4572)
					(clearance 0.1143)
				)
			)
		)
	)
	(footprint ""
		(layer "F.Cu")
		(at 78.74 43.688)
		(property "Reference" "C138"
			(at -0.22733 -1.397 90)
			(unlocked yes)
			(layer "F.SilkS")
			(effects
				(font
					(size 0.7874 0.5842)
					(thickness 0.127)
				)
				(justify left)
			)
		)
		(property "Value" "10UF"
			(at -0.148158 1.7526 90)
			(unlocked yes)
			(layer "F.Fab")
			(hide yes)
			(effects
				(font
					(size 1.27 0.9652)
					(thickness 0.000001)
				)
				(justify left)
			)
		)
		(property "Device Type" "CAPC0058"
			(at -0.148158 1.7526 90)
			(unlocked yes)
			(layer "F.Fab")
			(hide yes)
			(effects
				(font
					(size 1.27 0.9652)
					(thickness 0.000001)
				)
				(justify left)
			)
		)
		(duplicate_pad_numbers_are_jumpers no)
		(fp_circle
			(center 0 0)
			(end 0.127 0)
			(stroke
				(width 0.2032)
				(type default)
			)
			(fill no)
			(layer "F.SilkS")
		)
		(fp_poly
			(pts
				(xy 0.7874 -1.6637) (xy -0.7874 -1.6637) (xy -0.7874 1.6637) (xy 0.7874 1.6637)
			)
			(stroke
				(width 0)
				(type default)
			)
			(fill no)
			(layer "F.CrtYd")
		)
		(fp_line
			(start -0.4064 -0.7874)
			(end 0.4064 -0.7874)
			(stroke
				(width 0.0254)
				(type default)
			)
			(layer "F.Fab")
		)
		(fp_line
			(start -0.4064 0.8128)
			(end -0.4064 -0.7874)
			(stroke
				(width 0.0254)
				(type default)
			)
			(layer "F.Fab")
		)
		(fp_line
			(start 0.4064 -0.7874)
			(end 0.4064 0.8128)
			(stroke
				(width 0.0254)
				(type default)
			)
			(layer "F.Fab")
		)
		(fp_line
			(start 0.4064 0.8128)
			(end -0.4064 0.8128)
			(stroke
				(width 0.0254)
				(type default)
			)
			(layer "F.Fab")
		)
		(pad "1" smd rect
			(at 0 -0.8001)
			(size 0.8636 0.9652)
			(layers "F.Cu" "F.Mask" "F.Paste")
			(net "DDR_VTT")
		)
		(pad "2" smd rect
			(at 0 0.8001)
			(size 0.8636 0.9652)
			(layers "F.Cu" "F.Mask" "F.Paste")
			(net "GND")
		)
	)
)
